(kicad_pcb
	(version 20260206)
	(generator "pcbnew")
	(generator_version "10.0")
	(general
		(thickness 1.6)
		(legacy_teardrops no)
	)
	(paper "A4")
	(title_block
		(title "Bryce Canyon_SCC_16316-1_OCP.brd")
		(comment 1 "Bryce Canyon / footprints 127-131 of 1561")
	)
	(layers
		(0 "F.Cu" signal "TOP")
		(4 "In1.Cu" signal "L2GND")
		(6 "In2.Cu" signal "L3")
		(8 "In3.Cu" signal "L4VCC")
		(10 "In4.Cu" signal "L5VCC")
		(12 "In5.Cu" signal "L6")
		(14 "In6.Cu" signal "L7GND")
		(2 "B.Cu" signal "BOTTOM")
		(9 "F.Adhes" user "F.Adhesive")
		(11 "B.Adhes" user "B.Adhesive")
		(13 "F.Paste" user "Package Geometry/Pastemask Top")
		(15 "B.Paste" user "Package Geometry/Pastemask Bottom")
		(5 "F.SilkS" user "Ref Des/Silkscreen Top")
		(7 "B.SilkS" user "Ref Des/Silkscreen Bottom")
		(1 "F.Mask" user "Board Geometry/Soldermask Top")
		(3 "B.Mask" user "Board Geometry/Soldermask Bottom")
		(17 "Dwgs.User" user "User.Drawings")
		(19 "Cmts.User" user "User.Comments")
		(21 "Eco1.User" user "User.Eco1")
		(23 "Eco2.User" user "User.Eco2")
		(25 "Edge.Cuts" user "Board Geometry/Outline")
		(27 "Margin" user)
		(31 "F.CrtYd" user "Package Geometry/Place Bound Top")
		(29 "B.CrtYd" user "Package Geometry/Place Bound Bottom")
		(35 "F.Fab" user "Ref Des/Assembly Top")
		(33 "B.Fab" user "Ref Des/Assembly Bottom")
	)
	(footprint ""
		(layer "F.Cu")
		(at 160.4772 -81.534 180)
		(property "Reference" "R323"
			(at 0 0 180)
			(layer "F.SilkS")
			(hide yes)
			(effects
				(font
					(size 1.27 1.27)
				)
			)
		)
		(property "Value" "1KR2F-3-GP"
			(at 0.064008 -3.993896 180)
			(unlocked yes)
			(layer "F.Fab")
			(hide yes)
			(effects
				(font
					(size 1.016 1.016)
					(thickness 0.1524)
				)
			)
		)
		(property "Device Type" "R402H16"
			(at 0.064008 -5.517896 180)
			(unlocked yes)
			(layer "F.Fab")
			(hide yes)
			(effects
				(font
					(size 1.016 1.016)
					(thickness 0.1524)
				)
			)
		)
		(duplicate_pad_numbers_are_jumpers no)
		(fp_line
			(start 0.508 -0.9398)
			(end -0.508 -0.9398)
			(stroke
				(width 0.1524)
				(type default)
			)
			(layer "F.SilkS")
		)
		(fp_line
			(start -0.508 -0.9398)
			(end -0.508 0.9398)
			(stroke
				(width 0.1524)
				(type default)
			)
			(layer "F.SilkS")
		)
		(fp_rect
			(start -0.508 0.9398)
			(end 0.508 -0.9398)
			(stroke
				(width 0)
				(type default)
			)
			(fill no)
			(layer "F.CrtYd")
		)
		(fp_rect
			(start -0.508 0.9398)
			(end 0.508 -0.9398)
			(stroke
				(width 0)
				(type default)
			)
			(fill no)
			(layer "F.Fab")
		)
		(pad "1" smd custom
			(at 0 -0.4445 180)
			(size 0.1397 0.1397)
			(layers "F.Cu" "F.Mask" "F.Paste")
			(net "P0V9")
			(options
				(clearance outline)
				(anchor circle)
			)
			(primitives
				(gr_poly
					(pts
						(arc
							(start -0.1778 -0.2794)
							(mid -0.249642 -0.249642)
							(end -0.2794 -0.1778)
						)
						(arc
							(start -0.2794 0.1778)
							(mid -0.249642 0.249642)
							(end -0.1778 0.2794)
						)
						(arc
							(start 0.1778 0.2794)
							(mid 0.249642 0.249642)
							(end 0.2794 0.1778)
						)
						(arc
							(start 0.2794 -0.1778)
							(mid 0.249642 -0.249642)
							(end 0.1778 -0.2794)
						)
					)
					(width 0)
					(fill yes)
				)
			)
		)
		(pad "2" smd custom
			(at 0 0.4445 180)
			(size 0.1397 0.1397)
			(layers "F.Cu" "F.Mask" "F.Paste")
			(net "P0V9_SENSE")
			(options
				(clearance outline)
				(anchor circle)
			)
			(primitives
				(gr_poly
					(pts
						(arc
							(start -0.1778 -0.2794)
							(mid -0.249642 -0.249642)
							(end -0.2794 -0.1778)
						)
						(arc
							(start -0.2794 0.1778)
							(mid -0.249642 0.249642)
							(end -0.1778 0.2794)
						)
						(arc
							(start 0.1778 0.2794)
							(mid 0.249642 0.249642)
							(end 0.2794 0.1778)
						)
						(arc
							(start 0.2794 -0.1778)
							(mid 0.249642 -0.249642)
							(end 0.1778 -0.2794)
						)
					)
					(width 0)
					(fill yes)
				)
			)
		)
	)
	(footprint ""
		(layer "F.Cu")
		(at 62.7634 -54.229 -90)
		(property "Reference" "TC1"
			(at 0 0 270)
			(layer "F.SilkS")
			(hide yes)
			(effects
				(font
					(size 1.27 1.27)
				)
			)
		)
		(property "Value" "SE470UF2VDM-GP"
			(at 0 -9.6012 270)
			(unlocked yes)
			(layer "F.Fab")
			(hide yes)
			(effects
				(font
					(size 1.016 1.016)
					(thickness 0.1524)
				)
			)
		)
		(property "Device Type" "CT7343H83"
			(at 0 -11.1252 270)
			(unlocked yes)
			(layer "F.Fab")
			(hide yes)
			(effects
				(font
					(size 1.016 1.016)
					(thickness 0.1524)
				)
			)
		)
		(duplicate_pad_numbers_are_jumpers no)
		(fp_line
			(start -2.286 4.8768)
			(end -2.286 2.032)
			(stroke
				(width 0.1524)
				(type default)
			)
			(layer "F.SilkS")
		)
		(fp_line
			(start 2.286 4.8768)
			(end -2.286 4.8768)
			(stroke
				(width 0.1524)
				(type default)
			)
			(layer "F.SilkS")
		)
		(fp_line
			(start 2.286 2.032)
			(end 2.286 4.8768)
			(stroke
				(width 0.1524)
				(type default)
			)
			(layer "F.SilkS")
		)
		(fp_line
			(start 2.286 -2.032)
			(end 2.286 -4.8768)
			(stroke
				(width 0.1524)
				(type default)
			)
			(layer "F.SilkS")
		)
		(fp_line
			(start 2.1082 -4.699)
			(end -2.1082 -4.699)
			(stroke
				(width 0.508)
				(type default)
			)
			(layer "F.SilkS")
		)
		(fp_line
			(start -2.286 -4.8768)
			(end -2.286 -2.032)
			(stroke
				(width 0.1524)
				(type default)
			)
			(layer "F.SilkS")
		)
		(fp_line
			(start 2.286 -4.8768)
			(end -2.286 -4.8768)
			(stroke
				(width 0.1524)
				(type default)
			)
			(layer "F.SilkS")
		)
		(fp_rect
			(start -2.1463 3.6449)
			(end 2.1463 -3.6449)
			(stroke
				(width 0)
				(type default)
			)
			(fill no)
			(layer "F.CrtYd")
		)
		(fp_poly
			(pts
				(xy -2.54 4.953) (xy -2.54 4.2926) (xy -3.81 4.2926) (xy -3.81 -4.2926) (xy -2.54 -4.2926) (xy -2.54 -4.953)
				(xy 2.54 -4.953) (xy 2.54 -4.2926) (xy 3.81 -4.2926) (xy 3.81 -1.6256) (xy 2.1463 -1.6256) (xy 2.1463 -3.6449)
				(xy -2.1463 -3.6449) (xy -2.1463 3.6449) (xy 2.1463 3.6449) (xy 2.1463 -1.6129) (xy 3.81 -1.6129)
				(xy 3.81 4.2926) (xy 2.54 4.2926) (xy 2.54 4.953)
			)
			(stroke
				(width 0)
				(type default)
			)
			(fill no)
			(layer "F.CrtYd")
		)
		(fp_rect
			(start -2.54 4.953)
			(end 2.54 -4.953)
			(stroke
				(width 0)
				(type default)
			)
			(fill no)
			(layer "F.Fab")
		)
		(fp_rect
			(start -3.81 4.2926)
			(end -2.54 -4.2926)
			(stroke
				(width 0)
				(type default)
			)
			(fill no)
			(layer "F.Fab")
		)
		(fp_rect
			(start 2.54 4.2926)
			(end 3.81 -4.2926)
			(stroke
				(width 0)
				(type default)
			)
			(fill no)
			(layer "F.Fab")
		)
		(pad "1" smd rect
			(at 0 -3.1496 270)
			(size 2.413 2.286)
			(layers "F.Cu" "F.Mask" "F.Paste")
			(net "P0V9")
		)
		(pad "2" smd rect
			(at 0 3.1496 270)
			(size 2.413 2.286)
			(layers "F.Cu" "F.Mask" "F.Paste")
			(net "GND")
		)
		(zone
			(layer "F.Cu")
			(hatch none 0.5)
			(connect_pads
				(clearance 0)
			)
			(min_thickness 0.25)
			(keepout
				(tracks allowed)
				(vias not_allowed)
				(pads allowed)
				(copperpour not_allowed)
				(footprints allowed)
			)
			(placement
				(enabled no)
				(sheetname "")
			)
			(fill
				(thermal_gap 0.5)
				(thermal_bridge_width 0.5)
				(island_removal_mode 0)
			)
			(polygon
				(pts
					(xy 58.166 -55.7403) (xy 58.166 -52.7177) (xy 61.0616 -52.7177) (xy 61.3918 -52.7177) (xy 61.3918 -55.7403)
					(xy 61.0616 -55.7403)
				)
			)
		)
		(zone
			(layer "F.Cu")
			(hatch none 0.5)
			(connect_pads
				(clearance 0)
			)
			(min_thickness 0.25)
			(keepout
				(tracks allowed)
				(vias not_allowed)
				(pads allowed)
				(copperpour not_allowed)
				(footprints allowed)
			)
			(placement
				(enabled no)
				(sheetname "")
			)
			(fill
				(thermal_gap 0.5)
				(thermal_bridge_width 0.5)
				(island_removal_mode 0)
			)
			(polygon
				(pts
					(xy 64.4525 -52.7177) (xy 67.3608 -52.7177) (xy 67.3608 -55.7403) (xy 64.4652 -55.7403) (xy 64.135 -55.7403)
					(xy 64.135 -52.7177)
				)
			)
		)
	)
	(footprint ""
		(layer "F.Cu")
		(at 73.533 -41.148 180)
		(property "Reference" "C283"
			(at 0 0 180)
			(layer "F.SilkS")
			(hide yes)
			(effects
				(font
					(size 1.27 1.27)
				)
			)
		)
		(property "Value" "SC100U6D3V6MX-GP"
			(at -0.0762 -5.1308 180)
			(unlocked yes)
			(layer "F.Fab")
			(hide yes)
			(effects
				(font
					(size 1.016 1.016)
					(thickness 0.1524)
				)
			)
		)
		(property "Device Type" "C1206H71"
			(at -0.127 -6.6548 180)
			(unlocked yes)
			(layer "F.Fab")
			(hide yes)
			(effects
				(font
					(size 1.016 1.016)
					(thickness 0.1524)
				)
			)
		)
		(duplicate_pad_numbers_are_jumpers no)
		(fp_line
			(start 1.016 2.2352)
			(end -1.016 2.2352)
			(stroke
				(width 0.1524)
				(type default)
			)
			(layer "F.SilkS")
		)
		(fp_line
			(start 1.016 0.8382)
			(end 1.016 2.2352)
			(stroke
				(width 0.1524)
				(type default)
			)
			(layer "F.SilkS")
		)
		(fp_line
			(start 1.016 -2.2352)
			(end 1.016 -0.8382)
			(stroke
				(width 0.1524)
				(type default)
			)
			(layer "F.SilkS")
		)
		(fp_line
			(start -1.016 2.2352)
			(end -1.016 0.8382)
			(stroke
				(width 0.1524)
				(type default)
			)
			(layer "F.SilkS")
		)
		(fp_line
			(start -1.016 -0.8382)
			(end -1.016 -2.2352)
			(stroke
				(width 0.1524)
				(type default)
			)
			(layer "F.SilkS")
		)
		(fp_line
			(start -1.016 -2.2352)
			(end 1.016 -2.2352)
			(stroke
				(width 0.1524)
				(type default)
			)
			(layer "F.SilkS")
		)
		(fp_rect
			(start -1.0922 2.3114)
			(end 1.0922 -2.3114)
			(stroke
				(width 0)
				(type default)
			)
			(fill no)
			(layer "F.CrtYd")
		)
		(fp_poly
			(pts
				(xy 1.0922 -2.3114) (xy 1.0922 2.3114) (xy -1.0922 2.3114) (xy -1.0922 -2.3114)
			)
			(stroke
				(width 0)
				(type default)
			)
			(fill no)
			(layer "F.Fab")
		)
		(pad "1" smd rect
			(at 0 -1.397 180)
			(size 1.651 1.27)
			(layers "F.Cu" "F.Mask" "F.Paste")
			(net "GB_VDDA")
		)
		(pad "2" smd rect
			(at 0 1.397 180)
			(size 1.651 1.27)
			(layers "F.Cu" "F.Mask" "F.Paste")
			(net "GND")
		)
	)
	(footprint ""
		(layer "F.Cu")
		(at 5.588 -94.831408 180)
		(property "Reference" "R425"
			(at 0 0 180)
			(layer "F.SilkS")
			(hide yes)
			(effects
				(font
					(size 1.27 1.27)
				)
			)
		)
		(property "Value" "200KR2F-L-GP"
			(at 0.064008 -3.993896 180)
			(unlocked yes)
			(layer "F.Fab")
			(hide yes)
			(effects
				(font
					(size 1.016 1.016)
					(thickness 0.1524)
				)
			)
		)
		(property "Device Type" "R402H16"
			(at 0.064008 -5.517896 180)
			(unlocked yes)
			(layer "F.Fab")
			(hide yes)
			(effects
				(font
					(size 1.016 1.016)
					(thickness 0.1524)
				)
			)
		)
		(duplicate_pad_numbers_are_jumpers no)
		(fp_line
			(start 0.508 -0.9398)
			(end -0.508 -0.9398)
			(stroke
				(width 0.1524)
				(type default)
			)
			(layer "F.SilkS")
		)
		(fp_line
			(start -0.508 -0.9398)
			(end -0.508 0.9398)
			(stroke
				(width 0.1524)
				(type default)
			)
			(layer "F.SilkS")
		)
		(fp_rect
			(start -0.508 0.9398)
			(end 0.508 -0.9398)
			(stroke
				(width 0)
				(type default)
			)
			(fill no)
			(layer "F.CrtYd")
		)
		(fp_rect
			(start -0.508 0.9398)
			(end 0.508 -0.9398)
			(stroke
				(width 0)
				(type default)
			)
			(fill no)
			(layer "F.Fab")
		)
		(pad "1" smd custom
			(at 0 -0.4445 180)
			(size 0.1397 0.1397)
			(layers "F.Cu" "F.Mask" "F.Paste")
			(net "LS_EN_U36")
			(options
				(clearance outline)
				(anchor circle)
			)
			(primitives
				(gr_poly
					(pts
						(arc
							(start -0.1778 -0.2794)
							(mid -0.249642 -0.249642)
							(end -0.2794 -0.1778)
						)
						(arc
							(start -0.2794 0.1778)
							(mid -0.249642 0.249642)
							(end -0.1778 0.2794)
						)
						(arc
							(start 0.1778 0.2794)
							(mid 0.249642 0.249642)
							(end 0.2794 0.1778)
						)
						(arc
							(start 0.2794 -0.1778)
							(mid 0.249642 -0.249642)
							(end 0.1778 -0.2794)
						)
					)
					(width 0)
					(fill yes)
				)
			)
		)
		(pad "2" smd custom
			(at 0 0.4445 180)
			(size 0.1397 0.1397)
			(layers "F.Cu" "F.Mask" "F.Paste")
			(net "P0V9_PG")
			(options
				(clearance outline)
				(anchor circle)
			)
			(primitives
				(gr_poly
					(pts
						(arc
							(start -0.1778 -0.2794)
							(mid -0.249642 -0.249642)
							(end -0.2794 -0.1778)
						)
						(arc
							(start -0.2794 0.1778)
							(mid -0.249642 0.249642)
							(end -0.1778 0.2794)
						)
						(arc
							(start 0.1778 0.2794)
							(mid 0.249642 0.249642)
							(end 0.2794 0.1778)
						)
						(arc
							(start 0.2794 -0.1778)
							(mid 0.249642 -0.249642)
							(end 0.1778 -0.2794)
						)
					)
					(width 0)
					(fill yes)
				)
			)
		)
	)
	(footprint ""
		(layer "F.Cu")
		(at 45.1612 -33.401 180)
		(property "Reference" "U8"
			(at 0 0 180)
			(layer "F.SilkS")
			(hide yes)
			(effects
				(font
					(size 1.27 1.27)
				)
			)
		)
		(property "Value" "TPS51219RTER-1-GP"
			(at -4.064 -6.722618 180)
			(unlocked yes)
			(layer "F.Fab")
			(hide yes)
			(effects
				(font
					(size 1.016 1.016)
					(thickness 0.1524)
				)
			)
		)
		(property "Device Type" "QFN16-G1D8-UH32"
			(at -4.064 -8.246618 180)
			(unlocked yes)
			(layer "F.Fab")
			(hide yes)
			(effects
				(font
					(size 1.016 1.016)
					(thickness 0.1524)
				)
			)
		)
		(duplicate_pad_numbers_are_jumpers no)
		(fp_line
			(start 2.5146 2.5146)
			(end 2.5146 1.2446)
			(stroke
				(width 0.1524)
				(type default)
			)
			(layer "F.SilkS")
		)
		(fp_line
			(start 2.287524 -0.260604)
			(end 2.795524 -0.260604)
			(stroke
				(width 0.1524)
				(type default)
			)
			(layer "F.SilkS")
		)
		(fp_line
			(start 1.2446 2.5146)
			(end 2.5146 2.5146)
			(stroke
				(width 0.1524)
				(type default)
			)
			(layer "F.SilkS")
		)
		(fp_line
			(start -0.248666 2.287524)
			(end -0.248666 3.049524)
			(stroke
				(width 0.1524)
				(type default)
			)
			(layer "F.SilkS")
		)
		(fp_line
			(start -1.2446 -2.5146)
			(end -2.5146 -2.5146)
			(stroke
				(width 0.1524)
				(type default)
			)
			(layer "F.SilkS")
		)
		(fp_line
			(start -2.287524 -0.753364)
			(end -2.795524 -0.753364)
			(stroke
				(width 0.1524)
				(type default)
			)
			(layer "F.SilkS")
		)
		(fp_line
			(start -2.5146 2.5146)
			(end -1.2446 2.5146)
			(stroke
				(width 0.1524)
				(type default)
			)
			(layer "F.SilkS")
		)
		(fp_line
			(start -2.5146 1.2446)
			(end -2.5146 2.5146)
			(stroke
				(width 0.1524)
				(type default)
			)
			(layer "F.SilkS")
		)
		(fp_line
			(start -2.5146 -2.5146)
			(end -2.5146 -1.2446)
			(stroke
				(width 0.1524)
				(type default)
			)
			(layer "F.SilkS")
		)
		(fp_poly
			(pts
				(xy 1.2446 -2.5146) (xy 2.5146 -2.5146) (xy 2.5146 -1.2446)
			)
			(stroke
				(width 0)
				(type default)
			)
			(fill yes)
			(layer "F.SilkS")
		)
		(fp_rect
			(start -1.4986 1.4986)
			(end 1.4986 -1.4986)
			(stroke
				(width 0)
				(type default)
			)
			(fill no)
			(layer "F.CrtYd")
		)
		(fp_poly
			(pts
				(xy -1.4986 -1.4986) (xy -2.5146 -1.4986) (xy -2.5146 -2.5146) (xy 2.5146 -2.5146) (xy 2.5146 2.5146)
				(xy -2.5146 2.5146) (xy -2.5146 -1.4859) (xy -1.4986 -1.4859) (xy -1.4986 1.4986) (xy 1.4986 1.4986)
				(xy 1.4986 -1.4986)
			)
			(stroke
				(width 0)
				(type default)
			)
			(fill no)
			(layer "F.CrtYd")
		)
		(fp_rect
			(start -2.5146 2.5146)
			(end 2.5146 -2.5146)
			(stroke
				(width 0)
				(type default)
			)
			(fill no)
			(layer "F.Fab")
		)
		(pad "1" smd rect
			(at 0.750062 -1.550924 180)
			(size 0.3048 0.9144)
			(layers "F.Cu" "F.Mask" "F.Paste")
			(net "P0V9_VREF")
		)
		(pad "2" smd rect
			(at 0.249936 -1.550924 180)
			(size 0.3048 0.9144)
			(layers "F.Cu" "F.Mask" "F.Paste")
			(net "P0V9_REFIN")
		)
		(pad "3" smd rect
			(at -0.249936 -1.550924 180)
			(size 0.3048 0.9144)
			(layers "F.Cu" "F.Mask" "F.Paste")
			(net "P0V9_GSNS")
		)
		(pad "4" smd rect
			(at -0.750062 -1.550924 180)
			(size 0.3048 0.9144)
			(layers "F.Cu" "F.Mask" "F.Paste")
			(net "P0V9_VSNS")
		)
		(pad "5" smd rect
			(at -1.550924 -0.750062 180)
			(size 0.9144 0.3048)
			(layers "F.Cu" "F.Mask" "F.Paste")
			(net "P0V9_COMP")
		)
		(pad "6" smd rect
			(at -1.550924 -0.249936 180)
			(size 0.9144 0.3048)
			(layers "F.Cu" "F.Mask" "F.Paste")
			(net "P0V9_TRIP")
		)
		(pad "7" smd rect
			(at -1.550924 0.249936 180)
			(size 0.9144 0.3048)
			(layers "F.Cu" "F.Mask" "F.Paste")
			(net "AGND_P0V9")
		)
		(pad "8" smd rect
			(at -1.550924 0.750062 180)
			(size 0.9144 0.3048)
			(layers "F.Cu" "F.Mask" "F.Paste")
			(net "GND")
		)
		(pad "9" smd rect
			(at -0.750062 1.550924 180)
			(size 0.3048 0.9144)
			(layers "F.Cu" "F.Mask" "F.Paste")
			(net "P0V9_V5")
		)
		(pad "10" smd rect
			(at -0.249936 1.550924 180)
			(size 0.3048 0.9144)
			(layers "F.Cu" "F.Mask" "F.Paste")
			(net "P0V9_DL")
		)
		(pad "11" smd rect
			(at 0.249936 1.550924 180)
			(size 0.3048 0.9144)
			(layers "F.Cu" "F.Mask" "F.Paste")
			(net "P0V9_DH")
		)
		(pad "12" smd rect
			(at 0.750062 1.550924 180)
			(size 0.3048 0.9144)
			(layers "F.Cu" "F.Mask" "F.Paste")
			(net "P0V9_SW")
		)
		(pad "13" smd rect
			(at 1.550924 0.750062 180)
			(size 0.9144 0.3048)
			(layers "F.Cu" "F.Mask" "F.Paste")
			(net "P0V9_BST")
		)
		(pad "14" smd rect
			(at 1.550924 0.249936 180)
			(size 0.9144 0.3048)
			(layers "F.Cu" "F.Mask" "F.Paste")
			(net "P0V9_EN")
		)
		(pad "15" smd rect
			(at 1.550924 -0.249936 180)
			(size 0.9144 0.3048)
			(layers "F.Cu" "F.Mask" "F.Paste")
			(net "P0V9_MODE")
		)
		(pad "16" smd rect
			(at 1.550924 -0.750062 180)
			(size 0.9144 0.3048)
			(layers "F.Cu" "F.Mask" "F.Paste")
			(net "P0V9_U8_PG")
		)
		(pad "17" smd rect
			(at 0 0 180)
			(size 1.778 1.778)
			(layers "F.Cu" "F.Mask" "F.Paste")
			(net "GND")
		)
	)
)
